(kicad_pcb
	(version 20260206)
	(generator "pcbnew")
	(generator_version "10.0")
	(general
		(thickness 1.6)
		(legacy_teardrops no)
	)
	(paper "A4")
	(title_block
		(title "Bryce Canyon_F.DPB_16315-1-OCP.brd")
		(comment 1 "Bryce Canyon / footprint 2183 of 2223 (IO2), pads 1-67 of 202")
	)
	(layers
		(0 "F.Cu" signal "TOP")
		(4 "In1.Cu" signal "L2GND")
		(6 "In2.Cu" signal "L3")
		(8 "In3.Cu" signal "L4GND")
		(10 "In4.Cu" signal "L5")
		(12 "In5.Cu" signal "L6VCC")
		(14 "In6.Cu" signal "L7VCC")
		(16 "In7.Cu" signal "L8")
		(18 "In8.Cu" signal "L9GND")
		(20 "In9.Cu" signal "L10")
		(22 "In10.Cu" signal "L11GND")
		(2 "B.Cu" signal "BOTTOM")
		(9 "F.Adhes" user "F.Adhesive")
		(11 "B.Adhes" user "B.Adhesive")
		(13 "F.Paste" user "Package Geometry/Pastemask Top")
		(15 "B.Paste" user "Package Geometry/Pastemask Bottom")
		(5 "F.SilkS" user "Ref Des/Silkscreen Top")
		(7 "B.SilkS" user "Ref Des/Silkscreen Bottom")
		(1 "F.Mask" user "Board Geometry/Soldermask Top")
		(3 "B.Mask" user "Board Geometry/Soldermask Bottom")
		(17 "Dwgs.User" user "User.Drawings")
		(19 "Cmts.User" user "User.Comments")
		(21 "Eco1.User" user "User.Eco1")
		(23 "Eco2.User" user "User.Eco2")
		(25 "Edge.Cuts" user "Board Geometry/Outline")
		(27 "Margin" user)
		(31 "F.CrtYd" user "Package Geometry/Place Bound Top")
		(29 "B.CrtYd" user "Package Geometry/Place Bound Bottom")
		(35 "F.Fab" user "Ref Des/Assembly Top")
		(33 "B.Fab" user "Ref Des/Assembly Bottom")
	)
	(footprint ""
		(layer "B.Cu")
		(at 389.349996 -30.550104 180)
		(property "Reference" "IO2"
			(at 0 0 0)
			(layer "B.SilkS")
			(hide yes)
			(effects
				(font
					(size 1.27 1.27)
				)
				(justify mirror)
			)
		)
		(property "Value" "DM-AMP-CONN200-13R-6-GP-01"
			(at 47.5488 -16.5862 180)
			(unlocked yes)
			(layer "B.Fab")
			(hide yes)
			(effects
				(font
					(size 1.016 1.016)
					(thickness 0.1524)
				)
				(justify mirror)
			)
		)
		(property "Device Type" "DMFIT-200P-384346H577-01"
			(at 47.5488 -18.1102 180)
			(unlocked yes)
			(layer "B.Fab")
			(hide yes)
			(effects
				(font
					(size 1.016 1.016)
					(thickness 0.1524)
				)
				(justify mirror)
			)
		)
		(duplicate_pad_numbers_are_jumpers no)
		(pad "" np_thru_hole circle
			(at 17.200118 -9.99998)
			(size 0.254 0.254)
			(drill 2.3876)
			(layers "*.Cu" "*.Mask")
			(clearance 1.4224)
			(thermal_gap 1.4224)
		)
		(pad "" np_thru_hole circle
			(at 17.200118 -2.469896)
			(size 0.254 0.254)
			(drill 2.4638)
			(layers "*.Cu" "*.Mask")
			(clearance 1.4605)
			(thermal_gap 1.4605)
		)
		(pad "A1" thru_hole circle
			(at 0 0)
			(size 0.762 0.762)
			(drill 0.359918)
			(layers "*.Cu" "*.Mask")
			(remove_unused_layers no)
			(net "PCIE_COMP_B_TO_IOM_B_CLK_2_DN")
			(clearance 0.1651)
			(thermal_gap 0.1651)
		)
		(pad "A2" thru_hole circle
			(at 1.800098 -0.999998)
			(size 0.762 0.762)
			(drill 0.359918)
			(layers "*.Cu" "*.Mask")
			(remove_unused_layers no)
			(net "I2C_BMC_B_MISC_SDA")
			(clearance 0.1651)
			(thermal_gap 0.1651)
		)
		(pad "A3" thru_hole circle
			(at 3.599942 0)
			(size 0.762 0.762)
			(drill 0.359918)
			(layers "*.Cu" "*.Mask")
			(remove_unused_layers no)
			(net "BMC_B_HEARTBEAT")
			(clearance 0.1651)
			(thermal_gap 0.1651)
		)
		(pad "A4" thru_hole circle
			(at 5.40004 -0.999998)
			(size 0.762 0.762)
			(drill 0.359918)
			(layers "*.Cu" "*.Mask")
			(remove_unused_layers no)
			(net "SCC_A_FULL_PWR_EN")
			(clearance 0.1651)
			(thermal_gap 0.1651)
		)
		(pad "A5" thru_hole circle
			(at 7.199884 0)
			(size 0.762 0.762)
			(drill 0.359918)
			(layers "*.Cu" "*.Mask")
			(remove_unused_layers no)
			(net "PCIE_COMP_B_TO_IOM_B_CLK_3_DN")
			(clearance 0.1651)
			(thermal_gap 0.1651)
		)
		(pad "A6" thru_hole circle
			(at 8.999982 -0.999998)
			(size 0.762 0.762)
			(drill 0.359918)
			(layers "*.Cu" "*.Mask")
			(remove_unused_layers no)
			(net "I2C_BMC_B_EXP_B_SDA")
			(clearance 0.1651)
			(thermal_gap 0.1651)
		)
		(pad "A7" thru_hole circle
			(at 10.80008 0)
			(size 0.762 0.762)
			(drill 0.359918)
			(layers "*.Cu" "*.Mask")
			(remove_unused_layers no)
			(net "P12V_B")
			(clearance 0.1651)
			(thermal_gap 0.1651)
		)
		(pad "A8" thru_hole circle
			(at 12.599924 -0.999998)
			(size 0.762 0.762)
			(drill 0.359918)
			(layers "*.Cu" "*.Mask")
			(remove_unused_layers no)
			(net "P12V_B")
			(clearance 0.1651)
			(thermal_gap 0.1651)
		)
		(pad "A9" thru_hole circle
			(at 21.599906 0)
			(size 0.762 0.762)
			(drill 0.359918)
			(layers "*.Cu" "*.Mask")
			(remove_unused_layers no)
			(net "PCIE_COMP_B_TO_IOM_B_CLK_4_DN")
			(clearance 0.1651)
			(thermal_gap 0.1651)
		)
		(pad "A10" thru_hole circle
			(at 23.400004 -0.999998)
			(size 0.762 0.762)
			(drill 0.359918)
			(layers "*.Cu" "*.Mask")
			(remove_unused_layers no)
			(net "IOM_B_SLOT_ID_1")
			(clearance 0.1651)
			(thermal_gap 0.1651)
		)
		(pad "A11" thru_hole circle
			(at 25.200102 0)
			(size 0.762 0.762)
			(drill 0.359918)
			(layers "*.Cu" "*.Mask")
			(remove_unused_layers no)
			(net "BMC_B_TO_EXP_B_RESET_N")
			(clearance 0.1651)
			(thermal_gap 0.1651)
		)
		(pad "A12" thru_hole circle
			(at 26.999946 -0.999998)
			(size 0.762 0.762)
			(drill 0.359918)
			(layers "*.Cu" "*.Mask")
			(remove_unused_layers no)
			(net "USB_COMP_B_DN")
			(clearance 0.1651)
			(thermal_gap 0.1651)
		)
		(pad "A13" thru_hole circle
			(at 28.800044 0)
			(size 0.762 0.762)
			(drill 0.359918)
			(layers "*.Cu" "*.Mask")
			(remove_unused_layers no)
			(net "COMP_B_TO_BMC_B_RESET_N")
			(clearance 0.1651)
			(thermal_gap 0.1651)
		)
		(pad "A14" thru_hole circle
			(at 30.599888 -0.999998)
			(size 0.762 0.762)
			(drill 0.359918)
			(layers "*.Cu" "*.Mask")
			(remove_unused_layers no)
			(net "I2C_DPB_B_SDA")
			(clearance 0.1651)
			(thermal_gap 0.1651)
		)
		(pad "A15" thru_hole circle
			(at 32.399986 0)
			(size 0.762 0.762)
			(drill 0.359918)
			(layers "*.Cu" "*.Mask")
			(remove_unused_layers no)
			(net "BMC_B_EXP_B_SPARE_1")
			(clearance 0.1651)
			(thermal_gap 0.1651)
		)
		(pad "A16" thru_hole circle
			(at 34.200084 -0.999998)
			(size 0.762 0.762)
			(drill 0.359918)
			(layers "*.Cu" "*.Mask")
			(remove_unused_layers no)
			(net "COMP_B_BMC_B_SPARE_1")
			(clearance 0.1651)
			(thermal_gap 0.1651)
		)
		(pad "B1" thru_hole circle
			(at 0 -1.400048)
			(size 0.762 0.762)
			(drill 0.359918)
			(layers "*.Cu" "*.Mask")
			(remove_unused_layers no)
			(net "PCIE_COMP_B_TO_IOM_B_CLK_2_DP")
			(clearance 0.1651)
			(thermal_gap 0.1651)
		)
		(pad "B2" thru_hole circle
			(at 1.800098 -2.400046)
			(size 0.762 0.762)
			(drill 0.359918)
			(layers "*.Cu" "*.Mask")
			(remove_unused_layers no)
			(net "I2C_BMC_B_MISC_SCL")
			(clearance 0.1651)
			(thermal_gap 0.1651)
		)
		(pad "B3" thru_hole circle
			(at 3.599942 -1.400048)
			(size 0.762 0.762)
			(drill 0.359918)
			(layers "*.Cu" "*.Mask")
			(remove_unused_layers no)
			(net "BMC_A_HEARTBEAT")
			(clearance 0.1651)
			(thermal_gap 0.1651)
		)
		(pad "B4" thru_hole circle
			(at 5.40004 -2.400046)
			(size 0.762 0.762)
			(drill 0.359918)
			(layers "*.Cu" "*.Mask")
			(remove_unused_layers no)
			(net "SCC_B_FULL_PWR_EN")
			(clearance 0.1651)
			(thermal_gap 0.1651)
		)
		(pad "B5" thru_hole circle
			(at 7.199884 -1.400048)
			(size 0.762 0.762)
			(drill 0.359918)
			(layers "*.Cu" "*.Mask")
			(remove_unused_layers no)
			(net "PCIE_COMP_B_TO_IOM_B_CLK_3_DP")
			(clearance 0.1651)
			(thermal_gap 0.1651)
		)
		(pad "B6" thru_hole circle
			(at 8.999982 -2.400046)
			(size 0.762 0.762)
			(drill 0.359918)
			(layers "*.Cu" "*.Mask")
			(remove_unused_layers no)
			(net "I2C_BMC_B_EXP_B_SCL")
			(clearance 0.1651)
			(thermal_gap 0.1651)
		)
		(pad "B7" thru_hole circle
			(at 10.80008 -1.400048)
			(size 0.762 0.762)
			(drill 0.359918)
			(layers "*.Cu" "*.Mask")
			(remove_unused_layers no)
			(net "P12V_B_PGOOD")
			(clearance 0.1651)
			(thermal_gap 0.1651)
		)
		(pad "B8" thru_hole circle
			(at 12.599924 -2.400046)
			(size 0.762 0.762)
			(drill 0.359918)
			(layers "*.Cu" "*.Mask")
			(remove_unused_layers no)
			(net "P12V_B")
			(clearance 0.1651)
			(thermal_gap 0.1651)
		)
		(pad "B9" thru_hole circle
			(at 21.599906 -1.400048)
			(size 0.762 0.762)
			(drill 0.359918)
			(layers "*.Cu" "*.Mask")
			(remove_unused_layers no)
			(net "PCIE_COMP_B_TO_IOM_B_CLK_4_DP")
			(clearance 0.1651)
			(thermal_gap 0.1651)
		)
		(pad "B10" thru_hole circle
			(at 23.400004 -2.400046)
			(size 0.762 0.762)
			(drill 0.359918)
			(layers "*.Cu" "*.Mask")
			(remove_unused_layers no)
			(net "IOM_B_SLOT_ID_0")
			(clearance 0.1651)
			(thermal_gap 0.1651)
		)
		(pad "B11" thru_hole circle
			(at 25.200102 -1.400048)
			(size 0.762 0.762)
			(drill 0.359918)
			(layers "*.Cu" "*.Mask")
			(remove_unused_layers no)
			(net "BMC_B_MISC_ALERT_N")
			(clearance 0.1651)
			(thermal_gap 0.1651)
		)
		(pad "B12" thru_hole circle
			(at 26.999946 -2.400046)
			(size 0.762 0.762)
			(drill 0.359918)
			(layers "*.Cu" "*.Mask")
			(remove_unused_layers no)
			(net "USB_COMP_B_DP")
			(clearance 0.1651)
			(thermal_gap 0.1651)
		)
		(pad "B13" thru_hole circle
			(at 28.800044 -1.400048)
			(size 0.762 0.762)
			(drill 0.359918)
			(layers "*.Cu" "*.Mask")
			(remove_unused_layers no)
			(net "SYS_B_RESET_N")
			(clearance 0.1651)
			(thermal_gap 0.1651)
		)
		(pad "B14" thru_hole circle
			(at 30.599888 -2.400046)
			(size 0.762 0.762)
			(drill 0.359918)
			(layers "*.Cu" "*.Mask")
			(remove_unused_layers no)
			(net "I2C_DPB_B_SCL")
			(clearance 0.1651)
			(thermal_gap 0.1651)
		)
		(pad "B15" thru_hole circle
			(at 32.399986 -1.400048)
			(size 0.762 0.762)
			(drill 0.359918)
			(layers "*.Cu" "*.Mask")
			(remove_unused_layers no)
			(net "BMC_B_EXP_B_SPARE_0")
			(clearance 0.1651)
			(thermal_gap 0.1651)
		)
		(pad "B16" thru_hole circle
			(at 34.200084 -2.400046)
			(size 0.762 0.762)
			(drill 0.359918)
			(layers "*.Cu" "*.Mask")
			(remove_unused_layers no)
			(net "COMP_B_BMC_B_SPARE_0")
			(clearance 0.1651)
			(thermal_gap 0.1651)
		)
		(pad "C1" thru_hole circle
			(at 0 -3.599942)
			(size 0.762 0.762)
			(drill 0.359918)
			(layers "*.Cu" "*.Mask")
			(remove_unused_layers no)
			(net "IOM_B_MATED_N")
			(clearance 0.1651)
			(thermal_gap 0.1651)
		)
		(pad "C2" thru_hole circle
			(at 1.800098 -4.59994)
			(size 0.762 0.762)
			(drill 0.359918)
			(layers "*.Cu" "*.Mask")
			(remove_unused_layers no)
			(net "I2C_SCC_B_SDA")
			(clearance 0.1651)
			(thermal_gap 0.1651)
		)
		(pad "C3" thru_hole circle
			(at 3.599942 -3.599942)
			(size 0.762 0.762)
			(drill 0.359918)
			(layers "*.Cu" "*.Mask")
			(remove_unused_layers no)
			(net "SCC_A_HEARTBEAT")
			(clearance 0.1651)
			(thermal_gap 0.1651)
		)
		(pad "C4" thru_hole circle
			(at 5.40004 -4.59994)
			(size 0.762 0.762)
			(drill 0.359918)
			(layers "*.Cu" "*.Mask")
			(remove_unused_layers no)
			(net "IOM_B_PWR_LED")
			(clearance 0.1651)
			(thermal_gap 0.1651)
		)
		(pad "C5" thru_hole circle
			(at 7.199884 -3.599942)
			(size 0.762 0.762)
			(drill 0.359918)
			(layers "*.Cu" "*.Mask")
			(remove_unused_layers no)
			(net "IOM_B_INS_N")
			(clearance 0.1651)
			(thermal_gap 0.1651)
		)
		(pad "C6" thru_hole circle
			(at 8.999982 -4.59994)
			(size 0.762 0.762)
			(drill 0.359918)
			(layers "*.Cu" "*.Mask")
			(remove_unused_layers no)
			(net "I2C_BMC_B_EXP_A_SDA")
			(clearance 0.1651)
			(thermal_gap 0.1651)
		)
		(pad "C7" thru_hole circle
			(at 10.80008 -3.599942)
			(size 0.762 0.762)
			(drill 0.359918)
			(layers "*.Cu" "*.Mask")
			(remove_unused_layers no)
			(net "UART_SDB_B_RX")
			(clearance 0.1651)
			(thermal_gap 0.1651)
		)
		(pad "C8" thru_hole circle
			(at 12.599924 -4.59994)
			(size 0.762 0.762)
			(drill 0.359918)
			(layers "*.Cu" "*.Mask")
			(remove_unused_layers no)
			(net "P12V_B")
			(clearance 0.1651)
			(thermal_gap 0.1651)
		)
		(pad "C9" thru_hole circle
			(at 21.599906 -3.599942)
			(size 0.762 0.762)
			(drill 0.359918)
			(layers "*.Cu" "*.Mask")
			(remove_unused_layers no)
			(net "COMP_B_BMC_B_ALERT_N")
			(clearance 0.1651)
			(thermal_gap 0.1651)
		)
		(pad "C10" thru_hole circle
			(at 23.400004 -4.59994)
			(size 0.762 0.762)
			(drill 0.359918)
			(layers "*.Cu" "*.Mask")
			(remove_unused_layers no)
			(net "I2C_BMC_B_COMP_B_SDA_BUF")
			(clearance 0.1651)
			(thermal_gap 0.1651)
		)
		(pad "C11" thru_hole circle
			(at 25.200102 -3.599942)
			(size 0.762 0.762)
			(drill 0.359918)
			(layers "*.Cu" "*.Mask")
			(remove_unused_layers no)
			(net "UART_COMP_B_RX")
			(clearance 0.1651)
			(thermal_gap 0.1651)
		)
		(pad "C12" thru_hole circle
			(at 26.999946 -4.59994)
			(size 0.762 0.762)
			(drill 0.359918)
			(layers "*.Cu" "*.Mask")
			(remove_unused_layers no)
			(net "COMP_B_PWR_EN")
			(clearance 0.1651)
			(thermal_gap 0.1651)
		)
		(pad "C13" thru_hole circle
			(at 28.800044 -3.599942)
			(size 0.762 0.762)
			(drill 0.359918)
			(layers "*.Cu" "*.Mask")
			(remove_unused_layers no)
			(net "COMP_B_POWER_FAIL_N")
			(clearance 0.1651)
			(thermal_gap 0.1651)
		)
		(pad "C14" thru_hole circle
			(at 30.599888 -4.59994)
			(size 0.762 0.762)
			(drill 0.359918)
			(layers "*.Cu" "*.Mask")
			(remove_unused_layers no)
			(net "Net_16")
			(clearance 0.1651)
			(thermal_gap 0.1651)
		)
		(pad "C15" thru_hole circle
			(at 32.399986 -3.599942)
			(size 0.762 0.762)
			(drill 0.359918)
			(layers "*.Cu" "*.Mask")
			(remove_unused_layers no)
			(net "Net_17")
			(clearance 0.1651)
			(thermal_gap 0.1651)
		)
		(pad "C16" thru_hole circle
			(at 34.200084 -4.59994)
			(size 0.762 0.762)
			(drill 0.359918)
			(layers "*.Cu" "*.Mask")
			(remove_unused_layers no)
			(net "PWM_BMC_B_ZONE_C")
			(clearance 0.1651)
			(thermal_gap 0.1651)
		)
		(pad "D1" thru_hole circle
			(at 0 -4.99999)
			(size 0.762 0.762)
			(drill 0.359918)
			(layers "*.Cu" "*.Mask")
			(remove_unused_layers no)
			(net "PCIE_COMP_B_TO_IOM_B_RST_2")
			(clearance 0.1651)
			(thermal_gap 0.1651)
		)
		(pad "D2" thru_hole circle
			(at 1.800098 -5.999988)
			(size 0.762 0.762)
			(drill 0.359918)
			(layers "*.Cu" "*.Mask")
			(remove_unused_layers no)
			(net "I2C_SCC_B_SCL")
			(clearance 0.1651)
			(thermal_gap 0.1651)
		)
		(pad "D3" thru_hole circle
			(at 3.599942 -4.99999)
			(size 0.762 0.762)
			(drill 0.359918)
			(layers "*.Cu" "*.Mask")
			(remove_unused_layers no)
			(net "SCC_B_HEARTBEAT")
			(clearance 0.1651)
			(thermal_gap 0.1651)
		)
		(pad "D4" thru_hole circle
			(at 5.40004 -5.999988)
			(size 0.762 0.762)
			(drill 0.359918)
			(layers "*.Cu" "*.Mask")
			(remove_unused_layers no)
			(net "SCC_B_STBY_PWR_EN")
			(clearance 0.1651)
			(thermal_gap 0.1651)
		)
		(pad "D5" thru_hole circle
			(at 7.199884 -4.99999)
			(size 0.762 0.762)
			(drill 0.359918)
			(layers "*.Cu" "*.Mask")
			(remove_unused_layers no)
			(net "PCIE_COMP_B_TO_IOM_B_RST_3")
			(clearance 0.1651)
			(thermal_gap 0.1651)
		)
		(pad "D6" thru_hole circle
			(at 8.999982 -5.999988)
			(size 0.762 0.762)
			(drill 0.359918)
			(layers "*.Cu" "*.Mask")
			(remove_unused_layers no)
			(net "I2C_BMC_B_EXP_A_SCL")
			(clearance 0.1651)
			(thermal_gap 0.1651)
		)
		(pad "D7" thru_hole circle
			(at 10.80008 -4.99999)
			(size 0.762 0.762)
			(drill 0.359918)
			(layers "*.Cu" "*.Mask")
			(remove_unused_layers no)
			(net "UART_SDB_B_TX")
			(clearance 0.1651)
			(thermal_gap 0.1651)
		)
		(pad "D8" thru_hole circle
			(at 12.599924 -5.999988)
			(size 0.762 0.762)
			(drill 0.359918)
			(layers "*.Cu" "*.Mask")
			(remove_unused_layers no)
			(net "P12V_B")
			(clearance 0.1651)
			(thermal_gap 0.1651)
		)
		(pad "D9" thru_hole circle
			(at 21.599906 -4.99999)
			(size 0.762 0.762)
			(drill 0.359918)
			(layers "*.Cu" "*.Mask")
			(remove_unused_layers no)
			(net "PCIE_COMP_B_TO_IOM_B_RST_4")
			(clearance 0.1651)
			(thermal_gap 0.1651)
		)
		(pad "D10" thru_hole circle
			(at 23.400004 -5.999988)
			(size 0.762 0.762)
			(drill 0.359918)
			(layers "*.Cu" "*.Mask")
			(remove_unused_layers no)
			(net "I2C_BMC_B_COMP_B_SCL_BUF")
			(clearance 0.1651)
			(thermal_gap 0.1651)
		)
		(pad "D11" thru_hole circle
			(at 25.200102 -4.99999)
			(size 0.762 0.762)
			(drill 0.359918)
			(layers "*.Cu" "*.Mask")
			(remove_unused_layers no)
			(net "UART_COMP_B_TX")
			(clearance 0.1651)
			(thermal_gap 0.1651)
		)
		(pad "D12" thru_hole circle
			(at 26.999946 -5.999988)
			(size 0.762 0.762)
			(drill 0.359918)
			(layers "*.Cu" "*.Mask")
			(remove_unused_layers no)
			(net "SCC_A_TYPE_0")
			(clearance 0.1651)
			(thermal_gap 0.1651)
		)
		(pad "D13" thru_hole circle
			(at 28.800044 -4.99999)
			(size 0.762 0.762)
			(drill 0.359918)
			(layers "*.Cu" "*.Mask")
			(remove_unused_layers no)
			(net "COMP_B_FAST_THROTTLE_N")
			(clearance 0.1651)
			(thermal_gap 0.1651)
		)
		(pad "D14" thru_hole circle
			(at 30.599888 -5.999988)
			(size 0.762 0.762)
			(drill 0.359918)
			(layers "*.Cu" "*.Mask")
			(remove_unused_layers no)
			(net "COMP_B_PWR_BTN_N")
			(clearance 0.1651)
			(thermal_gap 0.1651)
		)
		(pad "D15" thru_hole circle
			(at 32.399986 -4.99999)
			(size 0.762 0.762)
			(drill 0.359918)
			(layers "*.Cu" "*.Mask")
			(remove_unused_layers no)
			(net "IOM_B_FAULT_LED")
			(clearance 0.1651)
			(thermal_gap 0.1651)
		)
		(pad "D16" thru_hole circle
			(at 34.200084 -5.999988)
			(size 0.762 0.762)
			(drill 0.359918)
			(layers "*.Cu" "*.Mask")
			(remove_unused_layers no)
			(net "PWM_BMC_B_ZONE_D")
			(clearance 0.1651)
			(thermal_gap 0.1651)
		)
		(pad "E1" thru_hole circle
			(at 0 -7.199884)
			(size 0.664718 0.664718)
			(drill 0.359918)
			(layers "*.Cu" "*.Mask")
			(remove_unused_layers no)
			(net "PCIE_IOM_B_TO_COMP_B_8_DN")
			(clearance 0.264414)
			(padstack
				(mode custom)
				(layer "In1.Cu"
					(shape circle)
					(size 0.664718 0.664718)
					(clearance 0.264414)
				)
				(layer "In2.Cu"
					(shape circle)
					(size 0.664718 0.664718)
					(clearance 0.264414)
				)
				(layer "In3.Cu"
					(shape circle)
					(size 0.664718 0.664718)
					(clearance 0.264414)
				)
				(layer "In4.Cu"
					(shape circle)
					(size 0.664718 0.664718)
					(clearance 0.264414)
				)
				(layer "In5.Cu"
					(shape circle)
					(size 0.664718 0.664718)
					(clearance 0.264414)
				)
				(layer "In6.Cu"
					(shape circle)
					(size 0.762 0.762)
					(clearance 0.1651)
				)
				(layer "In7.Cu"
					(shape circle)
					(size 0.762 0.762)
					(clearance 0.1651)
				)
				(layer "In8.Cu"
					(shape circle)
					(size 0.762 0.762)
					(clearance 0.1651)
				)
				(layer "In9.Cu"
					(shape circle)
					(size 0.762 0.762)
					(clearance 0.1651)
				)
				(layer "In10.Cu"
					(shape circle)
					(size 0.762 0.762)
					(clearance 0.1651)
				)
				(layer "B.Cu"
					(shape circle)
					(size 0.762 0.762)
					(thermal_gap 0.1651)
					(clearance 0.1651)
				)
			)
		)
	)
)
